(kicad_pcb
	(version 20260206)
	(generator "pcbnew")
	(generator_version "10.0")
	(general
		(thickness 1.6)
		(legacy_teardrops no)
	)
	(paper "A4")
	(title_block
		(title "Bryce Canyon_IOM_M2_16342-2_OCP.brd")
		(comment 1 "Bryce Canyon / footprints 91-95 of 1146")
	)
	(layers
		(0 "F.Cu" signal "TOP")
		(4 "In1.Cu" signal "L2GND")
		(6 "In2.Cu" signal "L3")
		(8 "In3.Cu" signal "L4VCC")
		(10 "In4.Cu" signal "L5VCC")
		(12 "In5.Cu" signal "L6")
		(14 "In6.Cu" signal "L7GND")
		(2 "B.Cu" signal "BOTTOM")
		(9 "F.Adhes" user "F.Adhesive")
		(11 "B.Adhes" user "B.Adhesive")
		(13 "F.Paste" user "Package Geometry/Pastemask Top")
		(15 "B.Paste" user "Package Geometry/Pastemask Bottom")
		(5 "F.SilkS" user "Ref Des/Silkscreen Top")
		(7 "B.SilkS" user "Ref Des/Silkscreen Bottom")
		(1 "F.Mask" user "Board Geometry/Soldermask Top")
		(3 "B.Mask" user "Board Geometry/Soldermask Bottom")
		(17 "Dwgs.User" user "User.Drawings")
		(19 "Cmts.User" user "User.Comments")
		(21 "Eco1.User" user "User.Eco1")
		(23 "Eco2.User" user "User.Eco2")
		(25 "Edge.Cuts" user "Board Geometry/Outline")
		(27 "Margin" user)
		(31 "F.CrtYd" user "Package Geometry/Place Bound Top")
		(29 "B.CrtYd" user "Package Geometry/Place Bound Bottom")
		(35 "F.Fab" user "Ref Des/Assembly Top")
		(33 "B.Fab" user "Ref Des/Assembly Bottom")
	)
	(footprint ""
		(layer "F.Cu")
		(at 54.280054 -172.699934)
		(property "Reference" "TPM1"
			(at 0 0 0)
			(layer "F.SilkS")
			(hide yes)
			(effects
				(font
					(size 1.27 1.27)
				)
			)
		)
		(property "Value" "FCI-CONN11-2-GP"
			(at -7.4803 1.3589 0)
			(unlocked yes)
			(layer "F.Fab")
			(hide yes)
			(effects
				(font
					(size 1.016 1.016)
					(thickness 0.1524)
				)
			)
		)
		(property "Device Type" "91932-31111LF"
			(at -7.4803 -0.1651 0)
			(unlocked yes)
			(layer "F.Fab")
			(hide yes)
			(effects
				(font
					(size 1.016 1.016)
					(thickness 0.1524)
				)
			)
		)
		(duplicate_pad_numbers_are_jumpers no)
		(fp_line
			(start -5.4102 -3.556)
			(end -5.4102 3.556)
			(stroke
				(width 0.1524)
				(type default)
			)
			(layer "F.SilkS")
		)
		(fp_line
			(start -5.4102 3.556)
			(end 5.4102 3.556)
			(stroke
				(width 0.1524)
				(type default)
			)
			(layer "F.SilkS")
		)
		(fp_line
			(start -2.8321 3.6449)
			(end -2.2479 3.6449)
			(stroke
				(width 0.3302)
				(type default)
			)
			(layer "F.SilkS")
		)
		(fp_line
			(start 5.4102 -3.556)
			(end -5.4102 -3.556)
			(stroke
				(width 0.1524)
				(type default)
			)
			(layer "F.SilkS")
		)
		(fp_line
			(start 5.4102 3.556)
			(end 5.4102 -3.556)
			(stroke
				(width 0.1524)
				(type default)
			)
			(layer "F.SilkS")
		)
		(fp_poly
			(pts
				(xy -2.591054 4.361434) (xy -3.226054 4.996434) (xy -1.956054 4.996434)
			)
			(stroke
				(width 0)
				(type default)
			)
			(fill yes)
			(layer "F.SilkS")
		)
		(fp_poly
			(pts
				(xy -2.8067 1.08839)
				(arc
					(start -2.8067 -0.422402)
					(mid -2.451868 -0.675672)
					(end -2.3114 -1.08839)
				)
				(arc
					(start 2.3114 -1.08839)
					(mid 2.451818 -0.675634)
					(end 2.8067 -0.422402)
				)
				(xy 2.8067 1.08839)
			)
			(stroke
				(width 0)
				(type default)
			)
			(fill yes)
			(layer "F.SilkS")
		)
		(fp_rect
			(start -5.1562 2.794)
			(end 5.1562 -2.794)
			(stroke
				(width 0)
				(type default)
			)
			(fill no)
			(layer "F.CrtYd")
		)
		(fp_poly
			(pts
				(xy 5.6642 -2.794) (xy -5.1562 -2.794) (xy -5.1562 2.794) (xy 5.1562 2.794) (xy 5.1562 -2.7813)
				(xy 5.6642 -2.7813) (xy 5.6642 3.81) (xy -5.6642 3.81) (xy -5.6642 -3.81) (xy 5.6642 -3.81)
			)
			(stroke
				(width 0)
				(type default)
			)
			(fill no)
			(layer "F.CrtYd")
		)
		(fp_rect
			(start -5.6642 3.81)
			(end 5.6642 -3.81)
			(stroke
				(width 0)
				(type default)
			)
			(fill no)
			(layer "F.Fab")
		)
		(pad "" np_thru_hole circle
			(at -3.0226 -1.100074)
			(size 0.254 0.254)
			(drill 0.8128)
			(layers "*.Cu" "*.Mask")
			(clearance 0.635)
			(thermal_gap 0.635)
		)
		(pad "" np_thru_hole circle
			(at 3.0226 -1.100074)
			(size 0.254 0.254)
			(drill 0.8128)
			(layers "*.Cu" "*.Mask")
			(clearance 0.635)
			(thermal_gap 0.635)
		)
		(pad "1" smd rect
			(at -2.500122 2.29489)
			(size 0.6096 2.0066)
			(layers "F.Cu" "F.Mask" "F.Paste")
			(net "Net_579")
		)
		(pad "2" smd rect
			(at -1.500124 2.29489)
			(size 0.6096 2.0066)
			(layers "F.Cu" "F.Mask" "F.Paste")
			(net "Net_578")
		)
		(pad "3" smd rect
			(at -0.500126 2.29489)
			(size 0.6096 2.0066)
			(layers "F.Cu" "F.Mask" "F.Paste")
			(net "Net_577")
		)
		(pad "4" smd rect
			(at 0.500126 2.29489)
			(size 0.6096 2.0066)
			(layers "F.Cu" "F.Mask" "F.Paste")
			(net "Net_576")
		)
		(pad "5" smd rect
			(at 1.500124 2.29489)
			(size 0.6096 2.0066)
			(layers "F.Cu" "F.Mask" "F.Paste")
			(net "Net_575")
		)
		(pad "6" smd rect
			(at 2.500122 2.29489)
			(size 0.6096 2.0066)
			(layers "F.Cu" "F.Mask" "F.Paste")
			(net "I2C_TPM_SDA")
		)
		(pad "7" smd rect
			(at -1.999996 -2.29489)
			(size 0.6096 2.0066)
			(layers "F.Cu" "F.Mask" "F.Paste")
			(net "P3V3_STBY")
		)
		(pad "8" smd rect
			(at -0.999998 -2.29489)
			(size 0.6096 2.0066)
			(layers "F.Cu" "F.Mask" "F.Paste")
			(net "FM_TPM_PRSNT_RST_N")
		)
		(pad "9" smd rect
			(at 0 -2.29489)
			(size 0.6096 2.0066)
			(layers "F.Cu" "F.Mask" "F.Paste")
			(net "Net_580")
		)
		(pad "10" smd rect
			(at 0.999998 -2.29489)
			(size 0.6096 2.0066)
			(layers "F.Cu" "F.Mask" "F.Paste")
			(net "I2C_TPM_SCL")
		)
		(pad "11" smd rect
			(at 1.999996 -2.29489)
			(size 0.6096 2.0066)
			(layers "F.Cu" "F.Mask" "F.Paste")
			(net "GND")
		)
		(pad "G1" smd custom
			(at -4.219956 0)
			(size 0.34925 0.34925)
			(layers "F.Cu" "F.Mask" "F.Paste")
			(net "GND")
			(options
				(clearance outline)
				(anchor circle)
			)
			(primitives
				(gr_poly
					(pts
						(xy -0.6985 2.921) (xy -0.6985 -2.921) (xy 0.6985 -2.921)
						(arc
							(start 0.6985 -1.610106)
							(mid 0.482924 -1.100074)
							(end 0.6985 -0.590042)
						)
						(xy 0.6985 2.921)
					)
					(width 0)
					(fill yes)
				)
			)
		)
		(pad "G2" smd custom
			(at 4.219956 0)
			(size 0.34925 0.34925)
			(layers "F.Cu" "F.Mask" "F.Paste")
			(net "GND")
			(options
				(clearance outline)
				(anchor circle)
			)
			(primitives
				(gr_poly
					(pts
						(xy -0.6985 2.921)
						(arc
							(start -0.6985 -0.590042)
							(mid -0.482924 -1.100074)
							(end -0.6985 -1.610106)
						)
						(xy -0.6985 -2.921) (xy 0.6985 -2.921) (xy 0.6985 2.921)
					)
					(width 0)
					(fill yes)
				)
			)
		)
		(zone
			(layer "F.Cu")
			(hatch none 0.5)
			(connect_pads
				(clearance 0)
			)
			(min_thickness 0.25)
			(keepout
				(tracks not_allowed)
				(vias allowed)
				(pads allowed)
				(copperpour not_allowed)
				(footprints allowed)
			)
			(placement
				(enabled no)
				(sheetname "")
			)
			(fill
				(thermal_gap 0.5)
				(thermal_bridge_width 0.5)
				(island_removal_mode 0)
			)
			(polygon
				(pts
					(xy 51.473354 -171.408344) (xy 57.086754 -171.408344) (xy 57.086754 -173.991524) (xy 51.473354 -173.991524)
				)
			)
		)
		(zone
			(layer "F.Cu")
			(hatch none 0.5)
			(connect_pads
				(clearance 0)
			)
			(min_thickness 0.25)
			(keepout
				(tracks allowed)
				(vias not_allowed)
				(pads allowed)
				(copperpour not_allowed)
				(footprints allowed)
			)
			(placement
				(enabled no)
				(sheetname "")
			)
			(fill
				(thermal_gap 0.5)
				(thermal_bridge_width 0.5)
				(island_removal_mode 0)
			)
			(polygon
				(pts
					(xy 51.473354 -171.408344) (xy 57.086754 -171.408344) (xy 57.086754 -173.991524) (xy 51.473354 -173.991524)
				)
			)
		)
		(zone
			(layer "F.Cu")
			(hatch none 0.5)
			(connect_pads
				(clearance 0)
			)
			(min_thickness 0.25)
			(keepout
				(tracks allowed)
				(vias not_allowed)
				(pads allowed)
				(copperpour not_allowed)
				(footprints allowed)
			)
			(placement
				(enabled no)
				(sheetname "")
			)
			(fill
				(thermal_gap 0.5)
				(thermal_bridge_width 0.5)
				(island_removal_mode 0)
			)
			(polygon
				(pts
					(xy 51.473354 -171.408344) (xy 57.086754 -171.408344) (xy 57.086754 -171.916344) (xy 51.473354 -171.916344)
				)
			)
		)
		(zone
			(layer "F.Cu")
			(hatch none 0.5)
			(connect_pads
				(clearance 0)
			)
			(min_thickness 0.25)
			(keepout
				(tracks allowed)
				(vias not_allowed)
				(pads allowed)
				(copperpour not_allowed)
				(footprints allowed)
			)
			(placement
				(enabled no)
				(sheetname "")
			)
			(fill
				(thermal_gap 0.5)
				(thermal_bridge_width 0.5)
				(island_removal_mode 0)
			)
			(polygon
				(pts
					(xy 51.968654 -173.483524) (xy 56.591454 -173.483524) (xy 56.591454 -173.991524) (xy 51.968654 -173.991524)
				)
			)
		)
		(zone
			(layers "F.Cu" "B.Cu" "In1.Cu" "In2.Cu" "In3.Cu" "In4.Cu" "In5.Cu" "In6.Cu")
			(hatch none 0.5)
			(connect_pads
				(clearance 0)
			)
			(min_thickness 0.25)
			(keepout
				(tracks not_allowed)
				(vias allowed)
				(pads allowed)
				(copperpour not_allowed)
				(footprints allowed)
			)
			(placement
				(enabled no)
				(sheetname "")
			)
			(fill
				(thermal_gap 0.5)
				(thermal_bridge_width 0.5)
				(island_removal_mode 0)
			)
			(polygon
				(pts
					(arc
						(start 51.968654 -173.800008)
						(mid 50.546254 -173.800008)
						(end 51.968654 -173.800008)
					)
				)
			)
		)
		(zone
			(layers "F.Cu" "B.Cu" "In1.Cu" "In2.Cu" "In3.Cu" "In4.Cu" "In5.Cu" "In6.Cu")
			(hatch none 0.5)
			(connect_pads
				(clearance 0)
			)
			(min_thickness 0.25)
			(keepout
				(tracks not_allowed)
				(vias allowed)
				(pads allowed)
				(copperpour not_allowed)
				(footprints allowed)
			)
			(placement
				(enabled no)
				(sheetname "")
			)
			(fill
				(thermal_gap 0.5)
				(thermal_bridge_width 0.5)
				(island_removal_mode 0)
			)
			(polygon
				(pts
					(arc
						(start 58.013854 -173.800008)
						(mid 56.591454 -173.800008)
						(end 58.013854 -173.800008)
					)
				)
			)
		)
	)
	(footprint ""
		(layer "F.Cu")
		(at 17.99971 -120.000014)
		(property "Reference" ""
			(at 0 0 0)
			(layer "F.SilkS")
			(hide yes)
			(effects
				(font
					(size 1.27 1.27)
				)
			)
		)
		(property "Value" "*"
			(at -6.38175 0.19685 0)
			(unlocked yes)
			(layer "F.Fab")
			(hide yes)
			(effects
				(font
					(size 1.016 1.016)
					(thickness 0.1524)
				)
			)
		)
		(duplicate_pad_numbers_are_jumpers no)
		(fp_poly
			(pts
				(arc
					(start 5.0673 0)
					(mid -5.0673 0)
					(end 5.0673 0)
				)
			)
			(stroke
				(width 0)
				(type default)
			)
			(fill no)
			(layer "B.CrtYd")
		)
		(fp_poly
			(pts
				(arc
					(start 5.0673 0)
					(mid -5.0673 0)
					(end 5.0673 0)
				)
			)
			(stroke
				(width 0)
				(type default)
			)
			(fill no)
			(layer "F.CrtYd")
		)
		(fp_poly
			(pts
				(arc
					(start 5.0673 0)
					(mid -5.0673 0)
					(end 5.0673 0)
				)
			)
			(stroke
				(width 0)
				(type default)
			)
			(fill no)
			(layer "B.Fab")
		)
		(fp_poly
			(pts
				(arc
					(start 5.0673 0)
					(mid -5.0673 0)
					(end 5.0673 0)
				)
			)
			(stroke
				(width 0)
				(type default)
			)
			(fill no)
			(layer "F.Fab")
		)
		(pad "1" thru_hole circle
			(at 0 0)
			(size 9.525 9.525)
			(drill 3.5052)
			(layers "*.Cu" "*.Mask")
			(remove_unused_layers no)
			(net "Net_38")
			(clearance -2.5019)
			(thermal_gap 0.3048)
			(padstack
				(mode front_inner_back)
				(layer "Inner"
					(shape circle)
					(size 3.9116 3.9116)
					(clearance 0.3048)
				)
				(layer "B.Cu"
					(shape circle)
					(size 9.525 9.525)
					(clearance -2.5019)
				)
			)
		)
	)
	(footprint ""
		(layer "F.Cu")
		(at 44.2976 -130.6576 180)
		(property "Reference" "R525"
			(at 0 0 180)
			(layer "F.SilkS")
			(hide yes)
			(effects
				(font
					(size 1.27 1.27)
				)
			)
		)
		(property "Value" "0R2J-2-GP"
			(at 0.064008 -3.993896 180)
			(unlocked yes)
			(layer "F.Fab")
			(hide yes)
			(effects
				(font
					(size 1.016 1.016)
					(thickness 0.1524)
				)
			)
		)
		(property "Device Type" "R402H16"
			(at 0.064008 -5.517896 180)
			(unlocked yes)
			(layer "F.Fab")
			(hide yes)
			(effects
				(font
					(size 1.016 1.016)
					(thickness 0.1524)
				)
			)
		)
		(duplicate_pad_numbers_are_jumpers no)
		(fp_line
			(start 0.508 -0.9398)
			(end -0.508 -0.9398)
			(stroke
				(width 0.1524)
				(type default)
			)
			(layer "F.SilkS")
		)
		(fp_line
			(start -0.508 -0.9398)
			(end -0.508 0.9398)
			(stroke
				(width 0.1524)
				(type default)
			)
			(layer "F.SilkS")
		)
		(fp_rect
			(start -0.508 0.9398)
			(end 0.508 -0.9398)
			(stroke
				(width 0)
				(type default)
			)
			(fill no)
			(layer "F.CrtYd")
		)
		(fp_rect
			(start -0.508 0.9398)
			(end 0.508 -0.9398)
			(stroke
				(width 0)
				(type default)
			)
			(fill no)
			(layer "F.Fab")
		)
		(pad "1" smd custom
			(at 0 -0.4445 180)
			(size 0.1397 0.1397)
			(layers "F.Cu" "F.Mask" "F.Paste")
			(net "PCIE_COMP_TO_IOM_RST_4")
			(options
				(clearance outline)
				(anchor circle)
			)
			(primitives
				(gr_poly
					(pts
						(arc
							(start -0.1778 -0.2794)
							(mid -0.249642 -0.249642)
							(end -0.2794 -0.1778)
						)
						(arc
							(start -0.2794 0.1778)
							(mid -0.249642 0.249642)
							(end -0.1778 0.2794)
						)
						(arc
							(start 0.1778 0.2794)
							(mid 0.249642 0.249642)
							(end 0.2794 0.1778)
						)
						(arc
							(start 0.2794 -0.1778)
							(mid 0.249642 -0.249642)
							(end 0.1778 -0.2794)
						)
					)
					(width 0)
					(fill yes)
				)
			)
		)
		(pad "2" smd custom
			(at 0 0.4445 180)
			(size 0.1397 0.1397)
			(layers "F.Cu" "F.Mask" "F.Paste")
			(net "PLTRST_R")
			(options
				(clearance outline)
				(anchor circle)
			)
			(primitives
				(gr_poly
					(pts
						(arc
							(start -0.1778 -0.2794)
							(mid -0.249642 -0.249642)
							(end -0.2794 -0.1778)
						)
						(arc
							(start -0.2794 0.1778)
							(mid -0.249642 0.249642)
							(end -0.1778 0.2794)
						)
						(arc
							(start 0.1778 0.2794)
							(mid 0.249642 0.249642)
							(end 0.2794 0.1778)
						)
						(arc
							(start 0.2794 -0.1778)
							(mid 0.249642 -0.249642)
							(end 0.1778 -0.2794)
						)
					)
					(width 0)
					(fill yes)
				)
			)
		)
	)
	(footprint ""
		(layer "F.Cu")
		(at 26.416 -124.206)
		(property "Reference" "R781"
			(at 0 0 0)
			(layer "F.SilkS")
			(hide yes)
			(effects
				(font
					(size 1.27 1.27)
				)
			)
		)
		(property "Value" "0R2J-2-GP"
			(at 0.064008 -3.993896 0)
			(unlocked yes)
			(layer "F.Fab")
			(hide yes)
			(effects
				(font
					(size 1.016 1.016)
					(thickness 0.1524)
				)
			)
		)
		(property "Device Type" "R402H16"
			(at 0.064008 -5.517896 0)
			(unlocked yes)
			(layer "F.Fab")
			(hide yes)
			(effects
				(font
					(size 1.016 1.016)
					(thickness 0.1524)
				)
			)
		)
		(duplicate_pad_numbers_are_jumpers no)
		(fp_line
			(start -0.508 -0.9398)
			(end -0.508 0.9398)
			(stroke
				(width 0.1524)
				(type default)
			)
			(layer "F.SilkS")
		)
		(fp_line
			(start 0.508 -0.9398)
			(end -0.508 -0.9398)
			(stroke
				(width 0.1524)
				(type default)
			)
			(layer "F.SilkS")
		)
		(fp_rect
			(start -0.508 0.9398)
			(end 0.508 -0.9398)
			(stroke
				(width 0)
				(type default)
			)
			(fill no)
			(layer "F.CrtYd")
		)
		(fp_rect
			(start -0.508 0.9398)
			(end 0.508 -0.9398)
			(stroke
				(width 0)
				(type default)
			)
			(fill no)
			(layer "F.Fab")
		)
		(pad "1" smd custom
			(at 0 -0.4445)
			(size 0.1397 0.1397)
			(layers "F.Cu" "F.Mask" "F.Paste")
			(net "FLA0_WP_N")
			(options
				(clearance outline)
				(anchor circle)
			)
			(primitives
				(gr_poly
					(pts
						(arc
							(start -0.1778 -0.2794)
							(mid -0.249642 -0.249642)
							(end -0.2794 -0.1778)
						)
						(arc
							(start -0.2794 0.1778)
							(mid -0.249642 0.249642)
							(end -0.1778 0.2794)
						)
						(arc
							(start 0.1778 0.2794)
							(mid 0.249642 0.249642)
							(end 0.2794 0.1778)
						)
						(arc
							(start 0.2794 -0.1778)
							(mid 0.249642 -0.249642)
							(end 0.1778 -0.2794)
						)
					)
					(width 0)
					(fill yes)
				)
			)
		)
		(pad "2" smd custom
			(at 0 0.4445)
			(size 0.1397 0.1397)
			(layers "F.Cu" "F.Mask" "F.Paste")
			(net "WP_ENABLE")
			(options
				(clearance outline)
				(anchor circle)
			)
			(primitives
				(gr_poly
					(pts
						(arc
							(start -0.1778 -0.2794)
							(mid -0.249642 -0.249642)
							(end -0.2794 -0.1778)
						)
						(arc
							(start -0.2794 0.1778)
							(mid -0.249642 0.249642)
							(end -0.1778 0.2794)
						)
						(arc
							(start 0.1778 0.2794)
							(mid 0.249642 0.249642)
							(end 0.2794 0.1778)
						)
						(arc
							(start 0.2794 -0.1778)
							(mid 0.249642 -0.249642)
							(end 0.1778 -0.2794)
						)
					)
					(width 0)
					(fill yes)
				)
			)
		)
	)
	(footprint ""
		(layer "F.Cu")
		(at 88.844628 -45.384212 90)
		(property "Reference" "R10"
			(at 0 0 90)
			(layer "F.SilkS")
			(hide yes)
			(effects
				(font
					(size 1.27 1.27)
				)
			)
		)
		(property "Value" "0R2J-2-GP"
			(at 0.064008 -3.993896 90)
			(unlocked yes)
			(layer "F.Fab")
			(hide yes)
			(effects
				(font
					(size 1.016 1.016)
					(thickness 0.1524)
				)
			)
		)
		(property "Device Type" "R402H16"
			(at 0.064008 -5.517896 90)
			(unlocked yes)
			(layer "F.Fab")
			(hide yes)
			(effects
				(font
					(size 1.016 1.016)
					(thickness 0.1524)
				)
			)
		)
		(duplicate_pad_numbers_are_jumpers no)
		(fp_line
			(start 0.508 -0.9398)
			(end -0.508 -0.9398)
			(stroke
				(width 0.1524)
				(type default)
			)
			(layer "F.SilkS")
		)
		(fp_line
			(start -0.508 -0.9398)
			(end -0.508 0.9398)
			(stroke
				(width 0.1524)
				(type default)
			)
			(layer "F.SilkS")
		)
		(fp_rect
			(start -0.508 0.9398)
			(end 0.508 -0.9398)
			(stroke
				(width 0)
				(type default)
			)
			(fill no)
			(layer "F.CrtYd")
		)
		(fp_rect
			(start -0.508 0.9398)
			(end 0.508 -0.9398)
			(stroke
				(width 0)
				(type default)
			)
			(fill no)
			(layer "F.Fab")
		)
		(pad "1" smd custom
			(at 0 -0.4445 90)
			(size 0.1397 0.1397)
			(layers "F.Cu" "F.Mask" "F.Paste")
			(net "MEZZA_PRSNT1_N")
			(options
				(clearance outline)
				(anchor circle)
			)
			(primitives
				(gr_poly
					(pts
						(arc
							(start -0.1778 -0.2794)
							(mid -0.249642 -0.249642)
							(end -0.2794 -0.1778)
						)
						(arc
							(start -0.2794 0.1778)
							(mid -0.249642 0.249642)
							(end -0.1778 0.2794)
						)
						(arc
							(start 0.1778 0.2794)
							(mid 0.249642 0.249642)
							(end 0.2794 0.1778)
						)
						(arc
							(start 0.2794 -0.1778)
							(mid 0.249642 -0.249642)
							(end 0.1778 -0.2794)
						)
					)
					(width 0)
					(fill yes)
				)
			)
		)
		(pad "2" smd custom
			(at 0 0.4445 90)
			(size 0.1397 0.1397)
			(layers "F.Cu" "F.Mask" "F.Paste")
			(net "GND")
			(options
				(clearance outline)
				(anchor circle)
			)
			(primitives
				(gr_poly
					(pts
						(arc
							(start -0.1778 -0.2794)
							(mid -0.249642 -0.249642)
							(end -0.2794 -0.1778)
						)
						(arc
							(start -0.2794 0.1778)
							(mid -0.249642 0.249642)
							(end -0.1778 0.2794)
						)
						(arc
							(start 0.1778 0.2794)
							(mid 0.249642 0.249642)
							(end 0.2794 0.1778)
						)
						(arc
							(start 0.2794 -0.1778)
							(mid 0.249642 -0.249642)
							(end 0.1778 -0.2794)
						)
					)
					(width 0)
					(fill yes)
				)
			)
		)
	)
)
